# T6G (Grand Teton) — schematic parts with pin connectivity, parts 2614–2614 of 8303; source: Cadence DE-HDL packaged netlist (pstxprt.dat, pstxnet.dat, pstchip.dat)

J37  SCONN288_DDR506112002KQ  IO  pkg DDR288S_1-1VXC  page 109
  1  VIN_BULK0  POWER  = P12V_MEM_CPU1
  2  RFU0  TRI  = NC
  3  VIN_MGMT  POWER  = P3V3_AUX
  4  HSCL  IN  = I3C_SPD_DDRL_CPU1_SCL
  5  HSDA  BI  = I3C_SPD_DDRL_CPU1_SDA
  6  VSS0  POWER  = GND
  7  DQ0_A  BI  = M_L_CPU1_SA_DQ<0>
  8  VSS1  POWER  = GND
  9  DQ1_A  BI  = M_L_CPU1_SA_DQ<1>
  10  VSS2  POWER  = GND
  11  DQS0_A_T  BI  = M_L_CPU1_SA_DQS_DP<0>
  12  DQS0_A_C  BI  = M_L_CPU1_SA_DQS_DN<0>
  13  VSS3  POWER  = GND
  14  DQ4_A  BI  = M_L_CPU1_SA_DQ<4>
  15  VSS4  POWER  = GND
  16  DQ5_A  BI  = M_L_CPU1_SA_DQ<5>
  17  VSS5  POWER  = GND
  18  DQ8_A  BI  = M_L_CPU1_SA_DQ<8>
  19  VSS6  POWER  = GND
  20  DQ9_A  BI  = M_L_CPU1_SA_DQ<9>
  21  VSS7  POWER  = GND
  22  DQS1_A_T  BI  = M_L_CPU1_SA_DQS_DP<1>
  23  DQS1_A_C  BI  = M_L_CPU1_SA_DQS_DN<1>
  24  VSS8  POWER  = GND
  25  DQ12_A  BI  = M_L_CPU1_SA_DQ<12>
  26  VSS9  POWER  = GND
  27  DQ13_A  BI  = M_L_CPU1_SA_DQ<13>
  28  VSS10  POWER  = GND
  29  DQ16_A  BI  = M_L_CPU1_SA_DQ<16>
  30  VSS11  POWER  = GND
  31  DQ17_A  BI  = M_L_CPU1_SA_DQ<17>
  32  VSS12  POWER  = GND
  33  DQS2_A_T  BI  = M_L_CPU1_SA_DQS_DP<2>
  34  DQS2_A_C  BI  = M_L_CPU1_SA_DQS_DN<2>
  35  VSS13  POWER  = GND
  36  DQ20_A  BI  = M_L_CPU1_SA_DQ<20>
  37  VSS14  POWER  = GND
  38  DQ21_A  BI  = M_L_CPU1_SA_DQ<21>
  39  VSS15  POWER  = GND
  40  DQ24_A  BI  = M_L_CPU1_SA_DQ<24>
  41  VSS16  POWER  = GND
  42  DQ25_A  BI  = M_L_CPU1_SA_DQ<25>
  43  VSS17  POWER  = GND
  44  DQS3_A_T  BI  = M_L_CPU1_SA_DQS_DP<3>
  45  DQS3_A_C  BI  = M_L_CPU1_SA_DQS_DN<3>
  46  VSS18  POWER  = GND
  47  DQ28_A  BI  = M_L_CPU1_SA_DQ<28>
  48  VSS19  POWER  = GND
  49  DQ29_A  BI  = M_L_CPU1_SA_DQ<29>
  50  VSS20  POWER  = GND
  51  CB0_A  BI  = M_L_CPU1_SA_CB<0>
  52  VSS21  POWER  = GND
  53  CB1_A  BI  = M_L_CPU1_SA_CB<1>
  54  VSS22  POWER  = GND
  55  DQS4_A_T  BI  = M_L_CPU1_SA_DQS_DP<4>
  56  DQS4_A_C  BI  = M_L_CPU1_SA_DQS_DN<4>
  57  VSS23  POWER  = GND
  58  CB4_A  BI  = M_L_CPU1_SA_CB<4>
  59  VSS24  POWER  = GND
  60  CB5_A  BI  = M_L_CPU1_SA_CB<5>
  61  VSS25  POWER  = GND
  62  ALERT_N  OUT  = M_L_CPU1_ALERT_N
  63  VSS26  POWER  = GND
  64  CS0_A_N  IN  = M_L_CPU1_SA_CS_N<0>
  65  VSS27  POWER  = GND
  66  CA0_A  IN  = M_L_CPU1_SA_CA<0>
  67  VSS28  POWER  = GND
  68  CA2_A  IN  = M_L_CPU1_SA_CA<2>
  69  VSS29  POWER  = GND
  70  CA4_A  IN  = M_L_CPU1_SA_CA<4>
  71  VSS30  POWER  = GND
  72  CA6_A  IN  = M_L_CPU1_SA_CA<6>
  73  VSS31  POWER  = GND
  74  PAR_A  IN  = M_L_CPU1_SA_PAR
  75  VSS32  POWER  = GND
  76  CA0_B  IN  = M_L_CPU1_SB_CA<0>
  77  VSS33  POWER  = GND
  78  CA2_B  IN  = M_L_CPU1_SB_CA<2>
  79  VSS34  POWER  = GND
  80  CA4_B  IN  = M_L_CPU1_SB_CA<4>
  81  VSS35  POWER  = GND
  82  CA6_B  IN  = M_L_CPU1_SB_CA<6>
  83  VSS36  POWER  = GND
  84  CS0_B_N  IN  = M_L_CPU1_SB_CS_N<0>
  85  VSS37  POWER  = GND
  86  \lbd||rsp_a_n\  OUT  = M_L_CPU1_SA_RSP<0>
  87  \lbs||rsp_b_n\  OUT  = M_L_CPU1_SB_RSP<0>
  88  VSS38  POWER  = GND
  89  CB4_B  BI  = M_L_CPU1_SB_CB<4>
  90  VSS39  POWER  = GND
  91  CB5_B  BI  = M_L_CPU1_SB_CB<5>
  92  VSS40  POWER  = GND
  93  \dqs9_b_t||tdqs9_b_t||dbi4_b_n\  BI  = M_L_CPU1_SB_DQS_DP<9>
  94  \dqs9_b_c||tdqs9_b_c\  BI  = M_L_CPU1_SB_DQS_DN<9>
  95  VSS41  POWER  = GND
  96  CB0_B  BI  = M_L_CPU1_SB_CB<0>
  97  VSS42  POWER  = GND
  98  CB1_B  BI  = M_L_CPU1_SB_CB<1>
  99  VSS43  POWER  = GND
  100  DQ0_B  BI  = M_L_CPU1_SB_DQ<0>
  101  VSS44  POWER  = GND
  102  DQ1_B  BI  = M_L_CPU1_SB_DQ<1>
  103  VSS45  POWER  = GND
  104  DQS0_B_T  BI  = M_L_CPU1_SB_DQS_DP<0>
  105  DQS0_B_C  BI  = M_L_CPU1_SB_DQS_DN<0>
  106  VSS46  POWER  = GND
  107  DQ4_B  BI  = M_L_CPU1_SB_DQ<4>
  108  VSS47  POWER  = GND
  109  DQ5_B  BI  = M_L_CPU1_SB_DQ<5>
  110  VSS48  POWER  = GND
  111  DQ8_B  BI  = M_L_CPU1_SB_DQ<8>
  112  VSS49  POWER  = GND
  113  DQ9_B  BI  = M_L_CPU1_SB_DQ<9>
  114  VSS50  POWER  = GND
  115  DQS1_B_T  BI  = M_L_CPU1_SB_DQS_DP<1>
  116  DQS1_B_C  BI  = M_L_CPU1_SB_DQS_DN<1>
  117  VSS51  POWER  = GND
  118  DQ12_B  BI  = M_L_CPU1_SB_DQ<12>
  119  VSS52  POWER  = GND
  120  DQ13_B  BI  = M_L_CPU1_SB_DQ<13>
  121  VSS53  POWER  = GND
  122  DQ16_B  BI  = M_L_CPU1_SB_DQ<16>
  123  VSS54  POWER  = GND
  124  DQ17_B  BI  = M_L_CPU1_SB_DQ<17>
  125  VSS55  POWER  = GND
  126  DQS2_B_T  BI  = M_L_CPU1_SB_DQS_DP<2>
  127  DQS2_B_C  BI  = M_L_CPU1_SB_DQS_DN<2>
  128  VSS56  POWER  = GND
  129  DQ20_B  BI  = M_L_CPU1_SB_DQ<20>
  130  VSS57  POWER  = GND
  131  DQ21_B  BI  = M_L_CPU1_SB_DQ<21>
  132  VSS58  POWER  = GND
  133  DQ24_B  BI  = M_L_CPU1_SB_DQ<24>
  134  VSS59  POWER  = GND
  135  DQ25_B  BI  = M_L_CPU1_SB_DQ<25>
  136  VSS60  POWER  = GND
  137  DQS3_B_T  BI  = M_L_CPU1_SB_DQS_DP<3>
  138  DQS3_B_C  BI  = M_L_CPU1_SB_DQS_DN<3>
  139  VSS61  POWER  = GND
  140  DQ28_B  BI  = M_L_CPU1_SB_DQ<28>
  141  VSS62  POWER  = GND
  142  DQ29_B  BI  = M_L_CPU1_SB_DQ<29>
  143  VSS63  POWER  = GND
  144  RFU1  TRI  = NC
  145  VIN_BULK1  POWER  = P12V_MEM_CPU1
  146  VIN_BULK2  POWER  = P12V_MEM_CPU1
  147  \pwr_good||fail_n\  BI  = PWRGD_CHL_CPU1_DIMM
  148  HAS  IN  = PD_CHL_CPU1_DIMM_SAA
  149  RFU2  TRI  = NC
  150  RFU3  TRI  = NC
  151  VSS64  POWER  = GND
  152  DQ2_A  BI  = M_L_CPU1_SA_DQ<2>
  153  VSS65  POWER  = GND
  154  DQ3_A  BI  = M_L_CPU1_SA_DQ<3>
  155  VSS66  POWER  = GND
  156  \dqs5_a_c||tdqs5_a_c||dqs5_a_t||tdqs5_a_t\  BI  = M_L_CPU1_SA_DQS_DN<5>
  157  \dqs5_a_t||tdqs5_a_t\  BI  = M_L_CPU1_SA_DQS_DP<5>
  158  VSS67  POWER  = GND
  159  DQ6_A  BI  = M_L_CPU1_SA_DQ<6>
  160  VSS68  POWER  = GND
  161  DQ7_A  BI  = M_L_CPU1_SA_DQ<7>
  162  VSS69  POWER  = GND
  163  DQ10_A  BI  = M_L_CPU1_SA_DQ<10>
  164  VSS70  POWER  = GND
  165  DQ11_A  BI  = M_L_CPU1_SA_DQ<11>
  166  VSS71  POWER  = GND
  167  \dqs6_a_c||tdqs6_a_c||dqs6_a_t||tdqs6_a_t\  BI  = M_L_CPU1_SA_DQS_DN<6>
  168  \dqs6_a_t||tdqs6_a_t\  BI  = M_L_CPU1_SA_DQS_DP<6>
  169  VSS72  POWER  = GND
  170  DQ14_A  BI  = M_L_CPU1_SA_DQ<14>
  171  VSS73  POWER  = GND
  172  DQ15_A  BI  = M_L_CPU1_SA_DQ<15>
  173  VSS74  POWER  = GND
  174  DQ18_A  BI  = M_L_CPU1_SA_DQ<18>
  175  VSS75  POWER  = GND
  176  DQ19_A  BI  = M_L_CPU1_SA_DQ<19>
  177  VSS76  POWER  = GND
  178  \dqs7_a_c||tdqs7_a_c\  BI  = M_L_CPU1_SA_DQS_DN<7>
  179  \dqs7_a_t||tdqs7_a_t\  BI  = M_L_CPU1_SA_DQS_DP<7>
  180  VSS77  POWER  = GND
  181  DQ22_A  BI  = M_L_CPU1_SA_DQ<22>
  182  VSS78  POWER  = GND
  183  DQ23_A  BI  = M_L_CPU1_SA_DQ<23>
  184  VSS79  POWER  = GND
  185  DQ26_A  BI  = M_L_CPU1_SA_DQ<26>
  186  VSS80  POWER  = GND
  187  DQ27_A  BI  = M_L_CPU1_SA_DQ<27>
  188  VSS81  POWER  = GND
  189  \dqs8_a_c||tdqs8_a_c\  BI  = M_L_CPU1_SA_DQS_DN<8>
  190  \dqs8_a_t||tdqs8_a_t\  BI  = M_L_CPU1_SA_DQS_DP<8>
  191  VSS82  POWER  = GND
  192  DQ30_A  BI  = M_L_CPU1_SA_DQ<30>
  193  VSS83  POWER  = GND
  194  DQ31_A  BI  = M_L_CPU1_SA_DQ<31>
  195  VSS84  POWER  = GND
  196  CB2_A  BI  = M_L_CPU1_SA_CB<2>
  197  VSS85  POWER  = GND
  198  CB3_A  BI  = M_L_CPU1_SA_CB<3>
  199  VSS86  POWER  = GND
  200  \dqs9_a_c||tdqs9_a_c\  BI  = M_L_CPU1_SA_DQS_DN<9>
  201  \dqs9_a_t||tdqs9_a_t\  BI  = M_L_CPU1_SA_DQS_DP<9>
  202  VSS87  POWER  = GND
  203  CB6_A  BI  = M_L_CPU1_SA_CB<6>
  204  VSS88  POWER  = GND
  205  CB7_A  BI  = M_L_CPU1_SA_CB<7>
  206  VSS89  POWER  = GND
  207  RESET_N  IN  = M_L_CPU1_RESET_N
  208  VSS90  POWER  = GND
  209  CS1_A_N  IN  = M_L_CPU1_SA_CS_N<1>
  210  VSS91  POWER  = GND
  211  CA1_A  IN  = M_L_CPU1_SA_CA<1>
  212  VSS92  POWER  = GND
  213  CA3_A  IN  = M_L_CPU1_SA_CA<3>
  214  VSS93  POWER  = GND
  215  CA5_A  IN  = M_L_CPU1_SA_CA<5>
  216  VSS94  POWER  = GND
  217  CK_T  IN  = M_L_CPU1_CLK_DP<0>
  218  CK_C  IN  = M_L_CPU1_CLK_DN<0>
  219  VSS95  POWER  = GND
  220  RFU4  TRI  = NC
  221  CA1_B  IN  = M_L_CPU1_SB_CA<1>
  222  VSS96  POWER  = GND
  223  CA3_B  IN  = M_L_CPU1_SB_CA<3>
  224  VSS97  POWER  = GND
  225  CA5_B  IN  = M_L_CPU1_SB_CA<5>
  226  VSS98  POWER  = GND
  227  PAR_B  IN  = M_L_CPU1_SB_PAR
  228  VSS99  POWER  = GND
  229  CS1_B_N  IN  = M_L_CPU1_SB_CS_N<1>
  230  VSS100  POWER  = GND
  231  RFU5  TRI  = NC
  232  RFU6  TRI  = NC
  233  VSS101  POWER  = GND
  234  CB6_B  BI  = M_L_CPU1_SB_CB<6>
  235  VSS102  POWER  = GND
  236  CB7_B  BI  = M_L_CPU1_SB_CB<7>
  237  VSS103  POWER  = GND
  238  DQS4_B_C  BI  = M_L_CPU1_SB_DQS_DN<4>
  239  DQS4_B_T  BI  = M_L_CPU1_SB_DQS_DP<4>
  240  VSS104  POWER  = GND
  241  CB2_B  BI  = M_L_CPU1_SB_CB<2>
  242  VSS105  POWER  = GND
  243  CB3_B  BI  = M_L_CPU1_SB_CB<3>
  244  VSS106  POWER  = GND
  245  DQ2_B  BI  = M_L_CPU1_SB_DQ<2>
  246  VSS107  POWER  = GND
  247  DQ3_B  BI  = M_L_CPU1_SB_DQ<3>
  248  VSS108  POWER  = GND
  249  \dqs5_b_c||tdqs5_b_c\  BI  = M_L_CPU1_SB_DQS_DN<5>
  250  \dqs5_b_t||tdqs5_b_t\  BI  = M_L_CPU1_SB_DQS_DP<5>
  251  VSS109  POWER  = GND
  252  DQ6_B  BI  = M_L_CPU1_SB_DQ<6>
  253  VSS110  POWER  = GND
  254  DQ7_B  BI  = M_L_CPU1_SB_DQ<7>
  255  VSS111  POWER  = GND
  256  DQ10_B  BI  = M_L_CPU1_SB_DQ<10>
  257  VSS112  POWER  = GND
  258  DQ11_B  BI  = M_L_CPU1_SB_DQ<11>
  259  VSS113  POWER  = GND
  260  \dqs6_b_c||tdqs6_b_c\  BI  = M_L_CPU1_SB_DQS_DN<6>
  261  \dqs6_b_t||tdqs6_b_t\  BI  = M_L_CPU1_SB_DQS_DP<6>
  262  VSS114  POWER  = GND
  263  DQ14_B  BI  = M_L_CPU1_SB_DQ<14>
  264  VSS115  POWER  = GND
  265  DQ15_B  BI  = M_L_CPU1_SB_DQ<15>
  266  VSS116  POWER  = GND
  267  DQ18_B  BI  = M_L_CPU1_SB_DQ<18>
  268  VSS117  POWER  = GND
  269  DQ19_B  BI  = M_L_CPU1_SB_DQ<19>
  270  VSS118  POWER  = GND
  271  \dqs7_b_c||tdqs7_b_c\  BI  = M_L_CPU1_SB_DQS_DN<7>
  272  \dqs7_b_t||tdqs7_b_t\  BI  = M_L_CPU1_SB_DQS_DP<7>
  273  VSS119  POWER  = GND
  274  DQ22_B  BI  = M_L_CPU1_SB_DQ<22>
  275  VSS120  POWER  = GND
  276  DQ23_B  BI  = M_L_CPU1_SB_DQ<23>
  277  VSS121  POWER  = GND
  278  DQ26_B  BI  = M_L_CPU1_SB_DQ<26>
  279  VSS122  POWER  = GND
  280  DQ27_B  BI  = M_L_CPU1_SB_DQ<27>
  281  VSS123  POWER  = GND
  282  \dqs8_b_c||tdqs8_b_c\  BI  = M_L_CPU1_SB_DQS_DN<8>
  283  \dqs8_b_t||tdqs8_b_t\  BI  = M_L_CPU1_SB_DQS_DP<8>
  284  VSS124  POWER  = GND
  285  DQ30_B  BI  = M_L_CPU1_SB_DQ<30>
  286  VSS125  POWER  = GND
  287  DQ31_B  BI  = M_L_CPU1_SB_DQ<31>
  288  VSS126  POWER  = GND
  G1  G1  POWER  = GND
  G2  G2  POWER  = GND
  G3  G3  POWER  = GND
